(kicad_pcb
	(version 20260206)
	(generator "pcbnew")
	(generator_version "10.0")
	(general
		(thickness 1.6)
		(legacy_teardrops no)
	)
	(paper "A4")
	(title_block
		(title "timecard-production-celestica-r4006 — R4006-B0001-02_R01.brd")
		(comment 1 "Time Appliance Project (Time Card) / footprints 200-204 of 1113")
	)
	(layers
		(0 "F.Cu" signal "TOP")
		(4 "In1.Cu" signal "L02_GND1")
		(6 "In2.Cu" signal "L03_SIG1")
		(8 "In3.Cu" signal "L04_GND2")
		(10 "In4.Cu" signal "L05_VCC1")
		(12 "In5.Cu" signal "L06_VCC2")
		(14 "In6.Cu" signal "L07_GND3")
		(16 "In7.Cu" signal "L08_SIG2")
		(18 "In8.Cu" signal "L09_GND4")
		(2 "B.Cu" signal "BOTTOM")
		(9 "F.Adhes" user "F.Adhesive")
		(11 "B.Adhes" user "B.Adhesive")
		(13 "F.Paste" user "Package Geometry/Pastemask Top")
		(15 "B.Paste" user "Package Geometry/Pastemask Bottom")
		(5 "F.SilkS" user "Ref Des/Silkscreen Top")
		(7 "B.SilkS" user "Ref Des/Silkscreen Bottom")
		(1 "F.Mask" user "Board Geometry/Soldermask Top")
		(3 "B.Mask" user "Board Geometry/Soldermask Bottom")
		(17 "Dwgs.User" user "User.Drawings")
		(19 "Cmts.User" user "User.Comments")
		(21 "Eco1.User" user "User.Eco1")
		(23 "Eco2.User" user "User.Eco2")
		(25 "Edge.Cuts" user "Board Geometry/Outline")
		(27 "Margin" user)
		(31 "F.CrtYd" user "Package Geometry/Place Bound Top")
		(29 "B.CrtYd" user "Package Geometry/Place Bound Bottom")
		(35 "F.Fab" user "Ref Des/Assembly Top")
		(33 "B.Fab" user "Ref Des/Assembly Bottom")
	)
	(footprint ""
		(layer "F.Cu")
		(at 116.205 -61.976 90)
		(property "Reference" "R435"
			(at 3.302 0.92837 90)
			(unlocked yes)
			(layer "F.SilkS")
			(effects
				(font
					(size 0.7874 0.5842)
					(thickness 0.1524)
				)
			)
		)
		(property "Value" "VAL*"
			(at 0.02032 2.13233 90)
			(unlocked yes)
			(layer "F.Fab")
			(hide yes)
			(effects
				(font
					(size 0.7874 0.5842)
					(thickness 0.1524)
				)
			)
		)
		(property "Tolerance" "TOL*"
			(at 0.044704 3.05435 90)
			(unlocked yes)
			(layer "Cmts.User")
			(hide yes)
			(effects
				(font
					(size 0.7874 0.5842)
					(thickness 0.1524)
				)
			)
		)
		(property "User Part Number" "PARTNUM*"
			(at 0.02032 4.024884 90)
			(unlocked yes)
			(layer "Cmts.User")
			(hide yes)
			(effects
				(font
					(size 0.7874 0.5842)
					(thickness 0.1524)
				)
			)
		)
		(property "Device Type" "RESISTOR-G155-11003-01,100KOHMA"
			(at 0.008382 1.210564 90)
			(unlocked yes)
			(layer "F.Fab")
			(hide yes)
			(effects
				(font
					(size 0.7874 0.5842)
					(thickness 0.1524)
				)
			)
		)
		(duplicate_pad_numbers_are_jumpers no)
		(fp_line
			(start 1.143 -0.5588)
			(end -1.143 -0.5588)
			(stroke
				(width 0.1)
				(type default)
			)
			(layer "F.SilkS")
		)
		(fp_line
			(start -1.143 -0.5588)
			(end -1.143 0.5588)
			(stroke
				(width 0.1)
				(type default)
			)
			(layer "F.SilkS")
		)
		(fp_line
			(start 1.143 0.5588)
			(end 1.143 -0.5588)
			(stroke
				(width 0.1)
				(type default)
			)
			(layer "F.SilkS")
		)
		(fp_line
			(start -1.143 0.5588)
			(end 1.143 0.5588)
			(stroke
				(width 0.1)
				(type default)
			)
			(layer "F.SilkS")
		)
		(fp_poly
			(pts
				(xy -1.143 0.5588) (xy 1.143 0.5588) (xy 1.143 -0.5588) (xy -1.143 -0.5588)
			)
			(stroke
				(width 0)
				(type default)
			)
			(fill no)
			(layer "F.CrtYd")
		)
		(fp_line
			(start 0.508 -0.3048)
			(end -0.508 -0.3048)
			(stroke
				(width 0.1)
				(type default)
			)
			(layer "F.Fab")
		)
		(fp_line
			(start -0.508 -0.3048)
			(end -0.508 0.3048)
			(stroke
				(width 0.1)
				(type default)
			)
			(layer "F.Fab")
		)
		(fp_line
			(start 0.508 0.3048)
			(end 0.508 -0.3048)
			(stroke
				(width 0.1)
				(type default)
			)
			(layer "F.Fab")
		)
		(fp_line
			(start -0.508 0.3048)
			(end 0.508 0.3048)
			(stroke
				(width 0.1)
				(type default)
			)
			(layer "F.Fab")
		)
		(pad "1" smd rect
			(at -0.5334 0 90)
			(size 0.7112 0.6096)
			(layers "F.Cu" "F.Mask" "F.Paste")
			(net "FPGA_FLASH_DQ1_MISO")
		)
		(pad "2" smd rect
			(at 0.5334 0 90)
			(size 0.7112 0.6096)
			(layers "F.Cu" "F.Mask" "F.Paste")
			(net "XP3R3V_FPGA")
		)
		(zone
			(layer "F.Cu")
			(hatch none 0.5)
			(connect_pads
				(clearance 0)
			)
			(min_thickness 0.25)
			(keepout
				(tracks not_allowed)
				(vias allowed)
				(pads allowed)
				(copperpour not_allowed)
				(footprints allowed)
			)
			(placement
				(enabled no)
				(sheetname "")
			)
			(fill
				(thermal_gap 0.5)
				(thermal_bridge_width 0.5)
				(island_removal_mode 0)
			)
			(polygon
				(pts
					(xy 116.5098 -61.8998) (xy 116.5098 -62.0522) (xy 115.9002 -62.0522) (xy 115.9002 -61.8998)
				)
			)
		)
		(zone
			(layer "F.Cu")
			(hatch none 0.5)
			(connect_pads
				(clearance 0)
			)
			(min_thickness 0.25)
			(keepout
				(tracks allowed)
				(vias not_allowed)
				(pads allowed)
				(copperpour not_allowed)
				(footprints allowed)
			)
			(placement
				(enabled no)
				(sheetname "")
			)
			(fill
				(thermal_gap 0.5)
				(thermal_bridge_width 0.5)
				(island_removal_mode 0)
			)
			(polygon
				(pts
					(xy 116.5098 -61.8998) (xy 116.5098 -62.0522) (xy 115.9002 -62.0522) (xy 115.9002 -61.8998)
				)
			)
		)
	)
	(footprint ""
		(layer "F.Cu")
		(at 101.1428 -78.486 90)
		(property "Reference" "C190"
			(at 1.524 2.02057 90)
			(unlocked yes)
			(layer "F.SilkS")
			(effects
				(font
					(size 0.7874 0.5842)
					(thickness 0.1524)
				)
			)
		)
		(property "Value" "VAL*"
			(at 0.193548 2.13614 90)
			(unlocked yes)
			(layer "F.Fab")
			(hide yes)
			(effects
				(font
					(size 0.7874 0.5842)
					(thickness 0.1524)
				)
			)
		)
		(property "Tolerance" "TOL*"
			(at 0.216154 3.1496 90)
			(unlocked yes)
			(layer "Cmts.User")
			(hide yes)
			(effects
				(font
					(size 0.7874 0.5842)
					(thickness 0.1524)
				)
			)
		)
		(property "Device Type" "CAPACITOR-G104-0B103-EK,0.01UFA"
			(at 0.184404 1.180592 90)
			(unlocked yes)
			(layer "F.Fab")
			(hide yes)
			(effects
				(font
					(size 0.7874 0.5842)
					(thickness 0.1524)
				)
			)
		)
		(property "User Part Number" "PARTNUM*"
			(at 0.216154 4.185666 90)
			(unlocked yes)
			(layer "Cmts.User")
			(hide yes)
			(effects
				(font
					(size 0.7874 0.5842)
					(thickness 0.1524)
				)
			)
		)
		(duplicate_pad_numbers_are_jumpers no)
		(fp_line
			(start 0.671322 -0.4445)
			(end 0.671322 0.4445)
			(stroke
				(width 0.1)
				(type default)
			)
			(layer "F.SilkS")
		)
		(fp_line
			(start -0.671322 -0.4445)
			(end 0.671322 -0.4445)
			(stroke
				(width 0.1)
				(type default)
			)
			(layer "F.SilkS")
		)
		(fp_line
			(start 0.671322 0.4445)
			(end -0.671322 0.4445)
			(stroke
				(width 0.1)
				(type default)
			)
			(layer "F.SilkS")
		)
		(fp_line
			(start -0.671322 0.4445)
			(end -0.671322 -0.4445)
			(stroke
				(width 0.1)
				(type default)
			)
			(layer "F.SilkS")
		)
		(fp_rect
			(start 0.671322 -0.4445)
			(end -0.671322 0.4445)
			(stroke
				(width 0)
				(type default)
			)
			(fill no)
			(layer "F.CrtYd")
		)
		(fp_line
			(start 0.31496 -0.1651)
			(end -0.31496 -0.1651)
			(stroke
				(width 0.1)
				(type default)
			)
			(layer "F.Fab")
		)
		(fp_line
			(start -0.31496 -0.1651)
			(end -0.31496 0.1651)
			(stroke
				(width 0.1)
				(type default)
			)
			(layer "F.Fab")
		)
		(fp_line
			(start 0.31496 0.1651)
			(end 0.31496 -0.1651)
			(stroke
				(width 0.1)
				(type default)
			)
			(layer "F.Fab")
		)
		(fp_line
			(start -0.31496 0.1651)
			(end 0.31496 0.1651)
			(stroke
				(width 0.1)
				(type default)
			)
			(layer "F.Fab")
		)
		(pad "1" smd rect
			(at -0.264922 0 90)
			(size 0.3048 0.381)
			(layers "F.Cu" "F.Mask" "F.Paste")
			(net "XP1R2V_SS")
		)
		(pad "2" smd rect
			(at 0.264922 0 90)
			(size 0.3048 0.381)
			(layers "F.Cu" "F.Mask" "F.Paste")
			(net "SG")
		)
		(zone
			(layer "F.Cu")
			(hatch none 0.5)
			(connect_pads
				(clearance 0)
			)
			(min_thickness 0.25)
			(keepout
				(tracks allowed)
				(vias not_allowed)
				(pads allowed)
				(copperpour not_allowed)
				(footprints allowed)
			)
			(placement
				(enabled no)
				(sheetname "")
			)
			(fill
				(thermal_gap 0.5)
				(thermal_bridge_width 0.5)
				(island_removal_mode 0)
			)
			(polygon
				(pts
					(xy 100.9523 -78.598522) (xy 100.9523 -78.373478) (xy 101.3333 -78.373478) (xy 101.3333 -78.598522)
				)
			)
		)
	)
	(footprint ""
		(layer "F.Cu")
		(at 128.1938 -64.3636)
		(property "Reference" "C186"
			(at 0.889 5.24637 0)
			(unlocked yes)
			(layer "F.SilkS")
			(effects
				(font
					(size 0.7874 0.5842)
					(thickness 0.1524)
				)
			)
		)
		(property "Value" "VAL*"
			(at 0.0762 3.134106 0)
			(unlocked yes)
			(layer "F.Fab")
			(hide yes)
			(effects
				(font
					(size 0.7874 0.5842)
					(thickness 0.1524)
				)
			)
		)
		(property "Tolerance" "TOL*"
			(at 0.0762 4.048506 0)
			(unlocked yes)
			(layer "Cmts.User")
			(hide yes)
			(effects
				(font
					(size 0.7874 0.5842)
					(thickness 0.1524)
				)
			)
		)
		(property "User Part Number" "PARTNUM*"
			(at 0.1016 5.013706 0)
			(unlocked yes)
			(layer "Cmts.User")
			(hide yes)
			(effects
				(font
					(size 0.7874 0.5842)
					(thickness 0.1524)
				)
			)
		)
		(property "Device Type" "CAPACITOR-G107-0F106-EM,10UF,2A"
			(at 0.0508 2.194306 0)
			(unlocked yes)
			(layer "F.Fab")
			(hide yes)
			(effects
				(font
					(size 0.7874 0.5842)
					(thickness 0.1524)
				)
			)
		)
		(duplicate_pad_numbers_are_jumpers no)
		(fp_line
			(start -1.5748 -0.9398)
			(end -1.5748 0.9398)
			(stroke
				(width 0.1)
				(type default)
			)
			(layer "F.SilkS")
		)
		(fp_line
			(start -1.5748 0.9398)
			(end 1.5748 0.9398)
			(stroke
				(width 0.1)
				(type default)
			)
			(layer "F.SilkS")
		)
		(fp_line
			(start 1.5748 -0.9398)
			(end -1.5748 -0.9398)
			(stroke
				(width 0.1)
				(type default)
			)
			(layer "F.SilkS")
		)
		(fp_line
			(start 1.5748 0.9398)
			(end 1.5748 -0.9398)
			(stroke
				(width 0.1)
				(type default)
			)
			(layer "F.SilkS")
		)
		(fp_rect
			(start 1.5748 -0.9398)
			(end -1.5748 0.9398)
			(stroke
				(width 0)
				(type default)
			)
			(fill no)
			(layer "F.CrtYd")
		)
		(fp_line
			(start -1.016 -0.635)
			(end -1.016 0.635)
			(stroke
				(width 0.1)
				(type default)
			)
			(layer "F.Fab")
		)
		(fp_line
			(start -1.016 0.635)
			(end 1.016 0.635)
			(stroke
				(width 0.1)
				(type default)
			)
			(layer "F.Fab")
		)
		(fp_line
			(start 1.016 -0.635)
			(end -1.016 -0.635)
			(stroke
				(width 0.1)
				(type default)
			)
			(layer "F.Fab")
		)
		(fp_line
			(start 1.016 0.635)
			(end 1.016 -0.635)
			(stroke
				(width 0.1)
				(type default)
			)
			(layer "F.Fab")
		)
		(pad "1" smd rect
			(at -0.8382 0)
			(size 0.9652 1.3716)
			(layers "F.Cu" "F.Mask" "F.Paste")
			(net "XP1R8V_VIN")
		)
		(pad "2" smd rect
			(at 0.8382 0)
			(size 0.9652 1.3716)
			(layers "F.Cu" "F.Mask" "F.Paste")
			(net "SG")
		)
		(zone
			(layer "F.Cu")
			(hatch none 0.5)
			(connect_pads
				(clearance 0)
			)
			(min_thickness 0.25)
			(keepout
				(tracks allowed)
				(vias not_allowed)
				(pads allowed)
				(copperpour not_allowed)
				(footprints allowed)
			)
			(placement
				(enabled no)
				(sheetname "")
			)
			(fill
				(thermal_gap 0.5)
				(thermal_bridge_width 0.5)
				(island_removal_mode 0)
			)
			(polygon
				(pts
					(xy 128.4224 -64.9986) (xy 127.9652 -64.9986) (xy 127.9652 -63.7286) (xy 128.4224 -63.7286)
				)
			)
		)
	)
	(footprint ""
		(layer "F.Cu")
		(at 143.256 -59.436 90)
		(property "Reference" "C264"
			(at 3.175 -1.86563 90)
			(unlocked yes)
			(layer "F.SilkS")
			(effects
				(font
					(size 0.7874 0.5842)
					(thickness 0.1524)
				)
			)
		)
		(property "Value" "VAL*"
			(at 0.193548 2.13614 90)
			(unlocked yes)
			(layer "F.Fab")
			(hide yes)
			(effects
				(font
					(size 0.7874 0.5842)
					(thickness 0.1524)
				)
			)
		)
		(property "Tolerance" "TOL*"
			(at 0.216154 3.1496 90)
			(unlocked yes)
			(layer "Cmts.User")
			(hide yes)
			(effects
				(font
					(size 0.7874 0.5842)
					(thickness 0.1524)
				)
			)
		)
		(property "Device Type" "CAPACITOR-G104-0A180-FJ,18PF,5%"
			(at 0.184404 1.180592 90)
			(unlocked yes)
			(layer "F.Fab")
			(hide yes)
			(effects
				(font
					(size 0.7874 0.5842)
					(thickness 0.1524)
				)
			)
		)
		(property "User Part Number" "PARTNUM*"
			(at 0.216154 4.185666 90)
			(unlocked yes)
			(layer "Cmts.User")
			(hide yes)
			(effects
				(font
					(size 0.7874 0.5842)
					(thickness 0.1524)
				)
			)
		)
		(duplicate_pad_numbers_are_jumpers no)
		(fp_line
			(start 0.671322 -0.4445)
			(end 0.671322 0.4445)
			(stroke
				(width 0.1)
				(type default)
			)
			(layer "F.SilkS")
		)
		(fp_line
			(start -0.671322 -0.4445)
			(end 0.671322 -0.4445)
			(stroke
				(width 0.1)
				(type default)
			)
			(layer "F.SilkS")
		)
		(fp_line
			(start 0.671322 0.4445)
			(end -0.671322 0.4445)
			(stroke
				(width 0.1)
				(type default)
			)
			(layer "F.SilkS")
		)
		(fp_line
			(start -0.671322 0.4445)
			(end -0.671322 -0.4445)
			(stroke
				(width 0.1)
				(type default)
			)
			(layer "F.SilkS")
		)
		(fp_rect
			(start -0.671322 -0.4445)
			(end 0.671322 0.4445)
			(stroke
				(width 0)
				(type default)
			)
			(fill no)
			(layer "F.CrtYd")
		)
		(fp_line
			(start 0.31496 -0.1651)
			(end -0.31496 -0.1651)
			(stroke
				(width 0.1)
				(type default)
			)
			(layer "F.Fab")
		)
		(fp_line
			(start -0.31496 -0.1651)
			(end -0.31496 0.1651)
			(stroke
				(width 0.1)
				(type default)
			)
			(layer "F.Fab")
		)
		(fp_line
			(start 0.31496 0.1651)
			(end 0.31496 -0.1651)
			(stroke
				(width 0.1)
				(type default)
			)
			(layer "F.Fab")
		)
		(fp_line
			(start -0.31496 0.1651)
			(end 0.31496 0.1651)
			(stroke
				(width 0.1)
				(type default)
			)
			(layer "F.Fab")
		)
		(pad "1" smd rect
			(at -0.264922 0 90)
			(size 0.3048 0.381)
			(layers "F.Cu" "F.Mask" "F.Paste")
			(net "XP1R0V_COMP")
		)
		(pad "2" smd rect
			(at 0.264922 0 90)
			(size 0.3048 0.381)
			(layers "F.Cu" "F.Mask" "F.Paste")
			(net "XP1R0V_AGND")
		)
		(zone
			(layer "F.Cu")
			(hatch none 0.5)
			(connect_pads
				(clearance 0)
			)
			(min_thickness 0.25)
			(keepout
				(tracks allowed)
				(vias not_allowed)
				(pads allowed)
				(copperpour not_allowed)
				(footprints allowed)
			)
			(placement
				(enabled no)
				(sheetname "")
			)
			(fill
				(thermal_gap 0.5)
				(thermal_bridge_width 0.5)
				(island_removal_mode 0)
			)
			(polygon
				(pts
					(xy 143.0655 -59.323478) (xy 143.4465 -59.323478) (xy 143.4465 -59.548522) (xy 143.0655 -59.548522)
				)
			)
		)
	)
	(footprint ""
		(layer "F.Cu")
		(at 16.852392 -68.8086 180)
		(property "Reference" "R70"
			(at 1.993392 0.24765 0)
			(unlocked yes)
			(layer "F.SilkS")
			(effects
				(font
					(size 0.635 0.4064)
					(thickness 0.1524)
				)
			)
		)
		(property "Value" "VAL*"
			(at 0.02032 2.13233 180)
			(unlocked yes)
			(layer "F.Fab")
			(hide yes)
			(effects
				(font
					(size 0.7874 0.5842)
					(thickness 0.1524)
				)
			)
		)
		(property "Tolerance" "TOL*"
			(at 0.044704 3.05435 180)
			(unlocked yes)
			(layer "Cmts.User")
			(hide yes)
			(effects
				(font
					(size 0.7874 0.5842)
					(thickness 0.1524)
				)
			)
		)
		(property "User Part Number" "PARTNUM*"
			(at 0.02032 4.024884 180)
			(unlocked yes)
			(layer "Cmts.User")
			(hide yes)
			(effects
				(font
					(size 0.7874 0.5842)
					(thickness 0.1524)
				)
			)
		)
		(property "Device Type" "RESISTOR-G155-14701-01,4.7KOHMA"
			(at 0.008382 1.210564 180)
			(unlocked yes)
			(layer "F.Fab")
			(hide yes)
			(effects
				(font
					(size 0.7874 0.5842)
					(thickness 0.1524)
				)
			)
		)
		(duplicate_pad_numbers_are_jumpers no)
		(fp_line
			(start 1.143 0.5588)
			(end 1.143 -0.5588)
			(stroke
				(width 0.1)
				(type default)
			)
			(layer "F.SilkS")
		)
		(fp_line
			(start 1.143 -0.5588)
			(end -1.143 -0.5588)
			(stroke
				(width 0.1)
				(type default)
			)
			(layer "F.SilkS")
		)
		(fp_line
			(start -1.143 0.5588)
			(end 1.143 0.5588)
			(stroke
				(width 0.1)
				(type default)
			)
			(layer "F.SilkS")
		)
		(fp_line
			(start -1.143 -0.5588)
			(end -1.143 0.5588)
			(stroke
				(width 0.1)
				(type default)
			)
			(layer "F.SilkS")
		)
		(fp_rect
			(start 1.143 0.5588)
			(end -1.143 -0.5588)
			(stroke
				(width 0)
				(type default)
			)
			(fill no)
			(layer "F.CrtYd")
		)
		(fp_line
			(start 0.508 0.3048)
			(end 0.508 -0.3048)
			(stroke
				(width 0.1)
				(type default)
			)
			(layer "F.Fab")
		)
		(fp_line
			(start 0.508 -0.3048)
			(end -0.508 -0.3048)
			(stroke
				(width 0.1)
				(type default)
			)
			(layer "F.Fab")
		)
		(fp_line
			(start -0.508 0.3048)
			(end 0.508 0.3048)
			(stroke
				(width 0.1)
				(type default)
			)
			(layer "F.Fab")
		)
		(fp_line
			(start -0.508 -0.3048)
			(end -0.508 0.3048)
			(stroke
				(width 0.1)
				(type default)
			)
			(layer "F.Fab")
		)
		(pad "1" smd rect
			(at -0.5334 0 180)
			(size 0.7112 0.6096)
			(layers "F.Cu" "F.Mask" "F.Paste")
			(net "XP1R8V_ICP10100")
		)
		(pad "2" smd rect
			(at 0.5334 0 180)
			(size 0.7112 0.6096)
			(layers "F.Cu" "F.Mask" "F.Paste")
			(net "BF_ICP10100_I2C_SDA")
		)
		(zone
			(layer "F.Cu")
			(hatch none 0.5)
			(connect_pads
				(clearance 0)
			)
			(min_thickness 0.25)
			(keepout
				(tracks allowed)
				(vias not_allowed)
				(pads allowed)
				(copperpour not_allowed)
				(footprints allowed)
			)
			(placement
				(enabled no)
				(sheetname "")
			)
			(fill
				(thermal_gap 0.5)
				(thermal_bridge_width 0.5)
				(island_removal_mode 0)
			)
			(polygon
				(pts
					(xy 16.776192 -69.1134) (xy 16.776192 -68.5038) (xy 16.928592 -68.5038) (xy 16.928592 -69.1134)
				)
			)
		)
	)
)
